(kicad_pcb
	(version 20260206)
	(generator "pcbnew")
	(generator_version "10.0")
	(general
		(thickness 1.6)
		(legacy_teardrops no)
	)
	(paper "A4")
	(title_block
		(title "04192023_DAF0TMB3IC0_F0TG_MB_C_brd_V02_OCP.brd")
		(comment 1 "Grand Teton / footprints 5325-5330 of 8354")
	)
	(layers
		(0 "F.Cu" signal "TOP")
		(4 "In1.Cu" signal "GND")
		(6 "In2.Cu" signal "IN1")
		(8 "In3.Cu" signal "GND1")
		(10 "In4.Cu" signal "IN2")
		(12 "In5.Cu" signal "GND2")
		(14 "In6.Cu" signal "IN3")
		(16 "In7.Cu" signal "GND3")
		(18 "In8.Cu" signal "VCC")
		(20 "In9.Cu" signal "VCC1")
		(22 "In10.Cu" signal "GND4")
		(24 "In11.Cu" signal "IN4")
		(26 "In12.Cu" signal "GND5")
		(28 "In13.Cu" signal "IN5")
		(30 "In14.Cu" signal "GND6")
		(32 "In15.Cu" signal "IN6")
		(34 "In16.Cu" signal "GND7")
		(2 "B.Cu" signal "BOTTOM")
		(9 "F.Adhes" user "F.Adhesive")
		(11 "B.Adhes" user "B.Adhesive")
		(13 "F.Paste" user "Package Geometry/Pastemask Top")
		(15 "B.Paste" user "Package Geometry/Pastemask Bottom")
		(5 "F.SilkS" user "Ref Des/Silkscreen Top")
		(7 "B.SilkS" user "Ref Des/Silkscreen Bottom")
		(1 "F.Mask" user "Board Geometry/Soldermask Top")
		(3 "B.Mask" user "Board Geometry/Soldermask Bottom")
		(17 "Dwgs.User" user "User.Drawings")
		(19 "Cmts.User" user "User.Comments")
		(21 "Eco1.User" user "User.Eco1")
		(23 "Eco2.User" user "User.Eco2")
		(25 "Edge.Cuts" user "Board Geometry/Outline")
		(27 "Margin" user)
		(31 "F.CrtYd" user "Package Geometry/Place Bound Top")
		(29 "B.CrtYd" user "Package Geometry/Place Bound Bottom")
		(35 "F.Fab" user "Ref Des/Assembly Top")
		(33 "B.Fab" user "Ref Des/Assembly Bottom")
	)
	(footprint ""
		(layer "B.Cu")
		(at 99.128834 -254.067564 180)
		(property "Reference" "C2672"
			(at 0 0 0)
			(layer "B.SilkS")
			(hide yes)
			(effects
				(font
					(size 1.27 1.27)
				)
				(justify mirror)
			)
		)
		(property "Value" ""
			(at 0 0 0)
			(layer "B.Fab")
			(effects
				(font
					(size 1.27 1.27)
				)
				(justify mirror)
			)
		)
		(duplicate_pad_numbers_are_jumpers no)
		(fp_line
			(start 0.7874 0.4064)
			(end 0.7874 -0.4064)
			(stroke
				(width 0.1524)
				(type default)
			)
			(layer "B.SilkS")
		)
		(fp_line
			(start 0.7874 -0.4064)
			(end -0.7874 -0.4064)
			(stroke
				(width 0.1524)
				(type default)
			)
			(layer "B.SilkS")
		)
		(fp_line
			(start -0.7874 0.4064)
			(end 0.7874 0.4064)
			(stroke
				(width 0.1524)
				(type default)
			)
			(layer "B.SilkS")
		)
		(fp_line
			(start -0.7874 -0.4064)
			(end -0.7874 0.4064)
			(stroke
				(width 0.1524)
				(type default)
			)
			(layer "B.SilkS")
		)
		(fp_line
			(start 0.67945 0.3048)
			(end 0.67945 -0.305054)
			(stroke
				(width 0.1)
				(type default)
			)
			(layer "B.Fab")
		)
		(fp_line
			(start 0.67945 -0.305054)
			(end 0.12065 -0.305054)
			(stroke
				(width 0.1)
				(type default)
			)
			(layer "B.Fab")
		)
		(fp_line
			(start 0.12065 0.3048)
			(end 0.67945 0.3048)
			(stroke
				(width 0.1)
				(type default)
			)
			(layer "B.Fab")
		)
		(fp_line
			(start 0.12065 0.2794)
			(end 0.12065 0.3048)
			(stroke
				(width 0.1)
				(type default)
			)
			(layer "B.Fab")
		)
		(fp_line
			(start 0.12065 -0.2794)
			(end -0.12065 -0.2794)
			(stroke
				(width 0.1)
				(type default)
			)
			(layer "B.Fab")
		)
		(fp_line
			(start 0.12065 -0.305054)
			(end 0.12065 -0.2794)
			(stroke
				(width 0.1)
				(type default)
			)
			(layer "B.Fab")
		)
		(fp_line
			(start -0.120396 0.3048)
			(end -0.120396 0.2794)
			(stroke
				(width 0.1)
				(type default)
			)
			(layer "B.Fab")
		)
		(fp_line
			(start -0.120396 0.2794)
			(end 0.12065 0.2794)
			(stroke
				(width 0.1)
				(type default)
			)
			(layer "B.Fab")
		)
		(fp_line
			(start -0.12065 -0.2794)
			(end -0.12065 -0.3048)
			(stroke
				(width 0.1)
				(type default)
			)
			(layer "B.Fab")
		)
		(fp_line
			(start -0.12065 -0.3048)
			(end -0.67945 -0.3048)
			(stroke
				(width 0.1)
				(type default)
			)
			(layer "B.Fab")
		)
		(fp_line
			(start -0.67945 0.3048)
			(end -0.120396 0.3048)
			(stroke
				(width 0.1)
				(type default)
			)
			(layer "B.Fab")
		)
		(fp_line
			(start -0.67945 -0.3048)
			(end -0.67945 0.3048)
			(stroke
				(width 0.1)
				(type default)
			)
			(layer "B.Fab")
		)
		(pad "1" smd circle
			(at 0.40005 0)
			(size 0 0)
			(layers "B.Cu" "B.Mask" "B.Paste")
			(net "PVDD18_S5_P1")
		)
		(pad "2" smd circle
			(at -0.40005 0)
			(size 0 0)
			(layers "B.Cu" "B.Mask" "B.Paste")
			(net "GND")
		)
	)
	(footprint ""
		(layer "B.Cu")
		(at 140.989558 -393.242546 180)
		(property "Reference" "R859"
			(at 0 0 0)
			(layer "B.SilkS")
			(hide yes)
			(effects
				(font
					(size 1.27 1.27)
				)
				(justify mirror)
			)
		)
		(property "Value" ""
			(at 0 0 0)
			(layer "B.Fab")
			(effects
				(font
					(size 1.27 1.27)
				)
				(justify mirror)
			)
		)
		(duplicate_pad_numbers_are_jumpers no)
		(fp_line
			(start 1.2954 0.5842)
			(end 1.2954 -0.5842)
			(stroke
				(width 0.1524)
				(type default)
			)
			(layer "B.SilkS")
		)
		(fp_line
			(start 1.2954 -0.5842)
			(end -1.2954 -0.5842)
			(stroke
				(width 0.1524)
				(type default)
			)
			(layer "B.SilkS")
		)
		(fp_line
			(start -1.2954 0.5842)
			(end 1.2954 0.5842)
			(stroke
				(width 0.1524)
				(type default)
			)
			(layer "B.SilkS")
		)
		(fp_line
			(start -1.2954 -0.5842)
			(end -1.2954 0.5842)
			(stroke
				(width 0.1524)
				(type default)
			)
			(layer "B.SilkS")
		)
		(fp_line
			(start 1.1938 0.4064)
			(end 1.1938 -0.406654)
			(stroke
				(width 0.1)
				(type default)
			)
			(layer "B.Fab")
		)
		(fp_line
			(start 1.1938 -0.406654)
			(end 0.8636 -0.406654)
			(stroke
				(width 0.1)
				(type default)
			)
			(layer "B.Fab")
		)
		(fp_line
			(start 0.8636 0.4572)
			(end 0.8636 0.4318)
			(stroke
				(width 0.1)
				(type default)
			)
			(layer "B.Fab")
		)
		(fp_line
			(start 0.8636 0.4318)
			(end 0.8636 0.4064)
			(stroke
				(width 0.1)
				(type default)
			)
			(layer "B.Fab")
		)
		(fp_line
			(start 0.8636 0.4064)
			(end 1.1938 0.4064)
			(stroke
				(width 0.1)
				(type default)
			)
			(layer "B.Fab")
		)
		(fp_line
			(start 0.8636 -0.406654)
			(end 0.8636 -0.4572)
			(stroke
				(width 0.1)
				(type default)
			)
			(layer "B.Fab")
		)
		(fp_line
			(start 0.8636 -0.4572)
			(end -0.8636 -0.4572)
			(stroke
				(width 0.1)
				(type default)
			)
			(layer "B.Fab")
		)
		(fp_line
			(start -0.8636 0.4572)
			(end 0.8636 0.4572)
			(stroke
				(width 0.1)
				(type default)
			)
			(layer "B.Fab")
		)
		(fp_line
			(start -0.8636 0.4064)
			(end -0.8636 0.4572)
			(stroke
				(width 0.1)
				(type default)
			)
			(layer "B.Fab")
		)
		(fp_line
			(start -0.8636 -0.406654)
			(end -1.1938 -0.406654)
			(stroke
				(width 0.1)
				(type default)
			)
			(layer "B.Fab")
		)
		(fp_line
			(start -0.8636 -0.4572)
			(end -0.8636 -0.406654)
			(stroke
				(width 0.1)
				(type default)
			)
			(layer "B.Fab")
		)
		(fp_line
			(start -1.1938 0.4064)
			(end -0.8636 0.4064)
			(stroke
				(width 0.1)
				(type default)
			)
			(layer "B.Fab")
		)
		(fp_line
			(start -1.1938 -0.406654)
			(end -1.1938 0.4064)
			(stroke
				(width 0.1)
				(type default)
			)
			(layer "B.Fab")
		)
		(pad "1" smd rect
			(at 0.7366 0 90)
			(size 0.7112 0.8128)
			(layers "B.Cu" "B.Mask" "B.Paste")
			(net "P0V9_CPU1_RT2_2A_2D")
		)
		(pad "2" smd rect
			(at -0.7366 0 90)
			(size 0.7112 0.8128)
			(layers "B.Cu" "B.Mask" "B.Paste")
			(net "P0V9_CPU1_RT2_2A")
		)
	)
	(footprint ""
		(layer "B.Cu")
		(at 75.51801 -148.451316 -90)
		(property "Reference" "PR397"
			(at 0 0 90)
			(layer "B.SilkS")
			(hide yes)
			(effects
				(font
					(size 1.27 1.27)
				)
				(justify mirror)
			)
		)
		(property "Value" ""
			(at 0 0 90)
			(layer "B.Fab")
			(effects
				(font
					(size 1.27 1.27)
				)
				(justify mirror)
			)
		)
		(duplicate_pad_numbers_are_jumpers no)
		(fp_line
			(start -0.7874 0.4064)
			(end 0.7874 0.4064)
			(stroke
				(width 0.1524)
				(type default)
			)
			(layer "B.SilkS")
		)
		(fp_line
			(start 0.7874 0.4064)
			(end 0.7874 -0.4064)
			(stroke
				(width 0.1524)
				(type default)
			)
			(layer "B.SilkS")
		)
		(fp_line
			(start -0.7874 -0.4064)
			(end -0.7874 0.4064)
			(stroke
				(width 0.1524)
				(type default)
			)
			(layer "B.SilkS")
		)
		(fp_line
			(start 0.7874 -0.4064)
			(end -0.7874 -0.4064)
			(stroke
				(width 0.1524)
				(type default)
			)
			(layer "B.SilkS")
		)
		(fp_line
			(start -0.67945 0.3048)
			(end -0.120396 0.3048)
			(stroke
				(width 0.1)
				(type default)
			)
			(layer "B.Fab")
		)
		(fp_line
			(start -0.120396 0.3048)
			(end -0.120396 0.2794)
			(stroke
				(width 0.1)
				(type default)
			)
			(layer "B.Fab")
		)
		(fp_line
			(start 0.12065 0.3048)
			(end 0.67945 0.3048)
			(stroke
				(width 0.1)
				(type default)
			)
			(layer "B.Fab")
		)
		(fp_line
			(start 0.67945 0.3048)
			(end 0.67945 -0.305054)
			(stroke
				(width 0.1)
				(type default)
			)
			(layer "B.Fab")
		)
		(fp_line
			(start -0.120396 0.2794)
			(end 0.12065 0.2794)
			(stroke
				(width 0.1)
				(type default)
			)
			(layer "B.Fab")
		)
		(fp_line
			(start 0.12065 0.2794)
			(end 0.12065 0.3048)
			(stroke
				(width 0.1)
				(type default)
			)
			(layer "B.Fab")
		)
		(fp_line
			(start -0.12065 -0.2794)
			(end -0.12065 -0.3048)
			(stroke
				(width 0.1)
				(type default)
			)
			(layer "B.Fab")
		)
		(fp_line
			(start 0.12065 -0.2794)
			(end -0.12065 -0.2794)
			(stroke
				(width 0.1)
				(type default)
			)
			(layer "B.Fab")
		)
		(fp_line
			(start -0.67945 -0.3048)
			(end -0.67945 0.3048)
			(stroke
				(width 0.1)
				(type default)
			)
			(layer "B.Fab")
		)
		(fp_line
			(start -0.12065 -0.3048)
			(end -0.67945 -0.3048)
			(stroke
				(width 0.1)
				(type default)
			)
			(layer "B.Fab")
		)
		(fp_line
			(start 0.12065 -0.305054)
			(end 0.12065 -0.2794)
			(stroke
				(width 0.1)
				(type default)
			)
			(layer "B.Fab")
		)
		(fp_line
			(start 0.67945 -0.305054)
			(end 0.12065 -0.305054)
			(stroke
				(width 0.1)
				(type default)
			)
			(layer "B.Fab")
		)
		(pad "1" smd circle
			(at 0.40005 0 90)
			(size 0 0)
			(layers "B.Cu" "B.Mask" "B.Paste")
			(net "P3V3_AUX")
		)
		(pad "2" smd circle
			(at -0.40005 0 90)
			(size 0 0)
			(layers "B.Cu" "B.Mask" "B.Paste")
			(net "PVDD18_S5_P1_VCC")
		)
	)
	(footprint ""
		(layer "B.Cu")
		(at 141.623542 -383.7432 180)
		(property "Reference" "R868"
			(at 0 0 0)
			(layer "B.SilkS")
			(hide yes)
			(effects
				(font
					(size 1.27 1.27)
				)
				(justify mirror)
			)
		)
		(property "Value" ""
			(at 0 0 0)
			(layer "B.Fab")
			(effects
				(font
					(size 1.27 1.27)
				)
				(justify mirror)
			)
		)
		(duplicate_pad_numbers_are_jumpers no)
		(fp_line
			(start 0.32512 0.175006)
			(end 0.32512 -0.175006)
			(stroke
				(width 0.1)
				(type default)
			)
			(layer "B.Fab")
		)
		(fp_line
			(start 0.32512 -0.175006)
			(end -0.32512 -0.175006)
			(stroke
				(width 0.1)
				(type default)
			)
			(layer "B.Fab")
		)
		(fp_line
			(start -0.32512 0.175006)
			(end 0.32512 0.175006)
			(stroke
				(width 0.1)
				(type default)
			)
			(layer "B.Fab")
		)
		(fp_line
			(start -0.32512 -0.175006)
			(end -0.32512 0.175006)
			(stroke
				(width 0.1)
				(type default)
			)
			(layer "B.Fab")
		)
		(pad "1" smd rect
			(at 0.2667 0)
			(size 0.3048 0.381)
			(layers "B.Cu" "B.Mask" "B.Paste")
			(net "P1V8_CPU1_RT_1D")
		)
		(pad "2" smd rect
			(at -0.2667 0 180)
			(size 0.3048 0.381)
			(layers "B.Cu" "B.Mask" "B.Paste")
			(net "RT_CPU1_P2_SCAN_MODE")
		)
	)
	(footprint ""
		(layer "B.Cu")
		(at 238.669576 -237.230666 -90)
		(property "Reference" "U6"
			(at 0.09271 2.847594 270)
			(unlocked yes)
			(layer "B.SilkS")
			(effects
				(font
					(size 0.7874 0.5842)
					(thickness 0.1524)
				)
				(justify mirror)
			)
		)
		(property "Value" ""
			(at 0 0 90)
			(layer "B.Fab")
			(effects
				(font
					(size 1.27 1.27)
				)
				(justify mirror)
			)
		)
		(duplicate_pad_numbers_are_jumpers no)
		(fp_line
			(start -1.03378 1.284478)
			(end 1.03378 1.284478)
			(stroke
				(width 0.1524)
				(type default)
			)
			(layer "B.SilkS")
		)
		(fp_line
			(start 1.03378 1.284478)
			(end 1.03378 -1.284478)
			(stroke
				(width 0.1524)
				(type default)
			)
			(layer "B.SilkS")
		)
		(fp_line
			(start -1.03378 -1.284478)
			(end -1.03378 1.284478)
			(stroke
				(width 0.1524)
				(type default)
			)
			(layer "B.SilkS")
		)
		(fp_line
			(start 1.03378 -1.284478)
			(end -1.03378 -1.284478)
			(stroke
				(width 0.1524)
				(type default)
			)
			(layer "B.SilkS")
		)
		(fp_poly
			(pts
				(xy 1.485646 -1.824482) (xy 1.20015 -1.211326) (xy 1.86182 -1.350772)
			)
			(stroke
				(width 0)
				(type default)
			)
			(fill yes)
			(layer "B.SilkS")
		)
		(fp_line
			(start -0.774954 1.02489)
			(end 0.774954 1.02489)
			(stroke
				(width 0.1)
				(type default)
			)
			(layer "B.Fab")
		)
		(fp_line
			(start 0.774954 1.02489)
			(end 0.774954 -1.02489)
			(stroke
				(width 0.1)
				(type default)
			)
			(layer "B.Fab")
		)
		(fp_line
			(start -0.774954 -1.02489)
			(end -0.774954 1.02489)
			(stroke
				(width 0.1)
				(type default)
			)
			(layer "B.Fab")
		)
		(fp_line
			(start 0.774954 -1.02489)
			(end -0.774954 -1.02489)
			(stroke
				(width 0.1)
				(type default)
			)
			(layer "B.Fab")
		)
		(fp_poly
			(pts
				(xy 1.201674 -0.750062) (xy 1.806702 -0.447548) (xy 1.806702 -1.052576)
			)
			(stroke
				(width 0)
				(type default)
			)
			(fill yes)
			(layer "B.Fab")
		)
		(pad "1" smd rect
			(at 0.64008 -0.750062)
			(size 0.3048 0.5334)
			(layers "B.Cu" "B.Mask" "B.Paste")
			(net "SMB_CPU0_SEC_R_SCL")
		)
		(pad "2" smd rect
			(at 0.64008 -0.249936)
			(size 0.254 0.5334)
			(layers "B.Cu" "B.Mask" "B.Paste")
			(net "SMB_CPU0_SEC_R_SDA")
		)
		(pad "3" smd rect
			(at 0.64008 0.249936)
			(size 0.254 0.5334)
			(layers "B.Cu" "B.Mask" "B.Paste")
			(net "SMB_CPU1_SEC_R_SCL")
		)
		(pad "4" smd rect
			(at 0.64008 0.750062)
			(size 0.3048 0.5334)
			(layers "B.Cu" "B.Mask" "B.Paste")
			(net "SMB_CPU1_SEC_R_SDA")
		)
		(pad "5" smd rect
			(at 0 0.839978 90)
			(size 0.3302 0.635)
			(layers "B.Cu" "B.Mask" "B.Paste")
			(net "GND")
		)
		(pad "6" smd rect
			(at -0.64008 0.750062)
			(size 0.3048 0.5334)
			(layers "B.Cu" "B.Mask" "B.Paste")
			(net "FM_SEC_MUX_OE_N")
		)
		(pad "7" smd rect
			(at -0.64008 0.249936)
			(size 0.254 0.5334)
			(layers "B.Cu" "B.Mask" "B.Paste")
			(net "SMB_CPU0_CPU1_SEC_SDA_R2")
		)
		(pad "8" smd rect
			(at -0.64008 -0.249936)
			(size 0.254 0.5334)
			(layers "B.Cu" "B.Mask" "B.Paste")
			(net "SMB_CPU0_CPU1_SEC_SCL_R2")
		)
		(pad "9" smd rect
			(at -0.64008 -0.750062)
			(size 0.3048 0.5334)
			(layers "B.Cu" "B.Mask" "B.Paste")
			(net "FM_SEC_MUX_SEL")
		)
		(pad "10" smd rect
			(at 0 -0.839978 90)
			(size 0.3302 0.635)
			(layers "B.Cu" "B.Mask" "B.Paste")
			(net "P3V3_AUX")
		)
	)
	(footprint ""
		(layer "B.Cu")
		(at 187.111894 -112.263174 180)
		(property "Reference" "C1175"
			(at 0 0 0)
			(layer "B.SilkS")
			(hide yes)
			(effects
				(font
					(size 1.27 1.27)
				)
				(justify mirror)
			)
		)
		(property "Value" ""
			(at 0 0 0)
			(layer "B.Fab")
			(effects
				(font
					(size 1.27 1.27)
				)
				(justify mirror)
			)
		)
		(duplicate_pad_numbers_are_jumpers no)
		(fp_line
			(start 0.69215 0.2921)
			(end 0.69215 -0.2921)
			(stroke
				(width 0.1524)
				(type default)
			)
			(layer "B.SilkS")
		)
		(fp_line
			(start 0.69215 -0.2921)
			(end -0.69215 -0.2921)
			(stroke
				(width 0.1524)
				(type default)
			)
			(layer "B.SilkS")
		)
		(fp_line
			(start -0.69215 0.2921)
			(end 0.69215 0.2921)
			(stroke
				(width 0.1524)
				(type default)
			)
			(layer "B.SilkS")
		)
		(fp_line
			(start -0.69215 -0.2921)
			(end -0.69215 0.2921)
			(stroke
				(width 0.1524)
				(type default)
			)
			(layer "B.SilkS")
		)
		(fp_line
			(start 0.51435 0.2794)
			(end 0.51435 -0.2794)
			(stroke
				(width 0.1)
				(type default)
			)
			(layer "B.Fab")
		)
		(fp_line
			(start 0.51435 -0.2794)
			(end -0.51435 -0.2794)
			(stroke
				(width 0.1)
				(type default)
			)
			(layer "B.Fab")
		)
		(fp_line
			(start -0.51435 0.2794)
			(end 0.51435 0.2794)
			(stroke
				(width 0.1)
				(type default)
			)
			(layer "B.Fab")
		)
		(fp_line
			(start -0.51435 -0.2794)
			(end -0.51435 0.2794)
			(stroke
				(width 0.1)
				(type default)
			)
			(layer "B.Fab")
		)
		(pad "1" smd circle
			(at 0.40005 0)
			(size 0 0)
			(layers "B.Cu" "B.Mask" "B.Paste")
			(net "P3V3_AUX")
		)
		(pad "2" smd circle
			(at -0.40005 0)
			(size 0 0)
			(layers "B.Cu" "B.Mask" "B.Paste")
			(net "GND")
		)
		(zone
			(layer "B.Cu")
			(hatch none 0.5)
			(connect_pads
				(clearance 0)
			)
			(min_thickness 0.25)
			(keepout
				(tracks not_allowed)
				(vias allowed)
				(pads allowed)
				(copperpour not_allowed)
				(footprints allowed)
			)
			(placement
				(enabled no)
				(sheetname "")
			)
			(fill
				(thermal_gap 0.5)
				(thermal_bridge_width 0.5)
				(island_removal_mode 0)
			)
			(polygon
				(pts
					(xy 186.921394 -112.17529) (xy 186.921394 -112.350804) (xy 187.012834 -112.40897) (xy 187.212224 -112.40897)
					(xy 187.302394 -112.350804) (xy 187.302394 -112.175544) (xy 187.212224 -112.117124) (xy 187.012834 -112.117124)
				)
			)
		)
	)
)
